(kicad_pcb
	(version 20260206)
	(generator "pcbnew")
	(generator_version "10.0")
	(general
		(thickness 1.6)
		(legacy_teardrops no)
	)
	(paper "A4")
	(title_block
		(title "04192023_DAF0TMB3IC0_F0TG_MB_C_brd_V02_OCP.brd")
		(comment 1 "Grand Teton / footprints 5181-5188 of 8354")
	)
	(layers
		(0 "F.Cu" signal "TOP")
		(4 "In1.Cu" signal "GND")
		(6 "In2.Cu" signal "IN1")
		(8 "In3.Cu" signal "GND1")
		(10 "In4.Cu" signal "IN2")
		(12 "In5.Cu" signal "GND2")
		(14 "In6.Cu" signal "IN3")
		(16 "In7.Cu" signal "GND3")
		(18 "In8.Cu" signal "VCC")
		(20 "In9.Cu" signal "VCC1")
		(22 "In10.Cu" signal "GND4")
		(24 "In11.Cu" signal "IN4")
		(26 "In12.Cu" signal "GND5")
		(28 "In13.Cu" signal "IN5")
		(30 "In14.Cu" signal "GND6")
		(32 "In15.Cu" signal "IN6")
		(34 "In16.Cu" signal "GND7")
		(2 "B.Cu" signal "BOTTOM")
		(9 "F.Adhes" user "F.Adhesive")
		(11 "B.Adhes" user "B.Adhesive")
		(13 "F.Paste" user "Package Geometry/Pastemask Top")
		(15 "B.Paste" user "Package Geometry/Pastemask Bottom")
		(5 "F.SilkS" user "Ref Des/Silkscreen Top")
		(7 "B.SilkS" user "Ref Des/Silkscreen Bottom")
		(1 "F.Mask" user "Board Geometry/Soldermask Top")
		(3 "B.Mask" user "Board Geometry/Soldermask Bottom")
		(17 "Dwgs.User" user "User.Drawings")
		(19 "Cmts.User" user "User.Comments")
		(21 "Eco1.User" user "User.Eco1")
		(23 "Eco2.User" user "User.Eco2")
		(25 "Edge.Cuts" user "Board Geometry/Outline")
		(27 "Margin" user)
		(31 "F.CrtYd" user "Package Geometry/Place Bound Top")
		(29 "B.CrtYd" user "Package Geometry/Place Bound Bottom")
		(35 "F.Fab" user "Ref Des/Assembly Top")
		(33 "B.Fab" user "Ref Des/Assembly Bottom")
	)
	(footprint ""
		(layer "B.Cu")
		(at 402.466302 -152.29078 -90)
		(property "Reference" "R4641"
			(at 0 0 90)
			(layer "B.SilkS")
			(hide yes)
			(effects
				(font
					(size 1.27 1.27)
				)
				(justify mirror)
			)
		)
		(property "Value" ""
			(at 0 0 90)
			(layer "B.Fab")
			(effects
				(font
					(size 1.27 1.27)
				)
				(justify mirror)
			)
		)
		(duplicate_pad_numbers_are_jumpers no)
		(fp_line
			(start -2.234946 0.9271)
			(end 2.234946 0.9271)
			(stroke
				(width 0.1524)
				(type default)
			)
			(layer "B.SilkS")
		)
		(fp_line
			(start 2.234946 0.9271)
			(end 2.234946 -0.9271)
			(stroke
				(width 0.1524)
				(type default)
			)
			(layer "B.SilkS")
		)
		(fp_line
			(start -2.234946 -0.9271)
			(end -2.234946 0.9271)
			(stroke
				(width 0.1524)
				(type default)
			)
			(layer "B.SilkS")
		)
		(fp_line
			(start 2.234946 -0.9271)
			(end -2.234946 -0.9271)
			(stroke
				(width 0.1524)
				(type default)
			)
			(layer "B.SilkS")
		)
		(fp_line
			(start -1.575054 0.824992)
			(end -1.575054 -0.824992)
			(stroke
				(width 0.1)
				(type default)
			)
			(layer "B.Fab")
		)
		(fp_line
			(start 1.575054 0.824992)
			(end -1.575054 0.824992)
			(stroke
				(width 0.1)
				(type default)
			)
			(layer "B.Fab")
		)
		(fp_line
			(start -1.575054 -0.824992)
			(end 1.575054 -0.824992)
			(stroke
				(width 0.1)
				(type default)
			)
			(layer "B.Fab")
		)
		(fp_line
			(start 1.575054 -0.824992)
			(end 1.575054 0.824992)
			(stroke
				(width 0.1)
				(type default)
			)
			(layer "B.Fab")
		)
		(pad "1" smd rect
			(at 1.599946 0 90)
			(size 1.016 1.6002)
			(layers "B.Cu" "B.Mask" "B.Paste")
			(net "P5V")
		)
		(pad "2" smd rect
			(at -1.599946 0 90)
			(size 1.016 1.6002)
			(layers "B.Cu" "B.Mask" "B.Paste")
			(net "VR_P5V_EN_D")
		)
	)
	(footprint ""
		(layer "B.Cu")
		(at 13.622782 -415.644584 -90)
		(property "Reference" "PR6542"
			(at 0 0 90)
			(layer "B.SilkS")
			(hide yes)
			(effects
				(font
					(size 1.27 1.27)
				)
				(justify mirror)
			)
		)
		(property "Value" ""
			(at 0 0 90)
			(layer "B.Fab")
			(effects
				(font
					(size 1.27 1.27)
				)
				(justify mirror)
			)
		)
		(duplicate_pad_numbers_are_jumpers no)
		(fp_line
			(start -0.7874 0.4064)
			(end 0.7874 0.4064)
			(stroke
				(width 0.1524)
				(type default)
			)
			(layer "B.SilkS")
		)
		(fp_line
			(start 0.7874 0.4064)
			(end 0.7874 -0.4064)
			(stroke
				(width 0.1524)
				(type default)
			)
			(layer "B.SilkS")
		)
		(fp_line
			(start -0.7874 -0.4064)
			(end -0.7874 0.4064)
			(stroke
				(width 0.1524)
				(type default)
			)
			(layer "B.SilkS")
		)
		(fp_line
			(start 0.7874 -0.4064)
			(end -0.7874 -0.4064)
			(stroke
				(width 0.1524)
				(type default)
			)
			(layer "B.SilkS")
		)
		(fp_line
			(start -0.67945 0.3048)
			(end -0.120396 0.3048)
			(stroke
				(width 0.1)
				(type default)
			)
			(layer "B.Fab")
		)
		(fp_line
			(start -0.120396 0.3048)
			(end -0.120396 0.2794)
			(stroke
				(width 0.1)
				(type default)
			)
			(layer "B.Fab")
		)
		(fp_line
			(start 0.12065 0.3048)
			(end 0.67945 0.3048)
			(stroke
				(width 0.1)
				(type default)
			)
			(layer "B.Fab")
		)
		(fp_line
			(start 0.67945 0.3048)
			(end 0.67945 -0.305054)
			(stroke
				(width 0.1)
				(type default)
			)
			(layer "B.Fab")
		)
		(fp_line
			(start -0.120396 0.2794)
			(end 0.12065 0.2794)
			(stroke
				(width 0.1)
				(type default)
			)
			(layer "B.Fab")
		)
		(fp_line
			(start 0.12065 0.2794)
			(end 0.12065 0.3048)
			(stroke
				(width 0.1)
				(type default)
			)
			(layer "B.Fab")
		)
		(fp_line
			(start -0.12065 -0.2794)
			(end -0.12065 -0.3048)
			(stroke
				(width 0.1)
				(type default)
			)
			(layer "B.Fab")
		)
		(fp_line
			(start 0.12065 -0.2794)
			(end -0.12065 -0.2794)
			(stroke
				(width 0.1)
				(type default)
			)
			(layer "B.Fab")
		)
		(fp_line
			(start -0.67945 -0.3048)
			(end -0.67945 0.3048)
			(stroke
				(width 0.1)
				(type default)
			)
			(layer "B.Fab")
		)
		(fp_line
			(start -0.12065 -0.3048)
			(end -0.67945 -0.3048)
			(stroke
				(width 0.1)
				(type default)
			)
			(layer "B.Fab")
		)
		(fp_line
			(start 0.12065 -0.305054)
			(end 0.12065 -0.2794)
			(stroke
				(width 0.1)
				(type default)
			)
			(layer "B.Fab")
		)
		(fp_line
			(start 0.67945 -0.305054)
			(end 0.12065 -0.305054)
			(stroke
				(width 0.1)
				(type default)
			)
			(layer "B.Fab")
		)
		(pad "1" smd circle
			(at 0.40005 0 90)
			(size 0 0)
			(layers "B.Cu" "B.Mask" "B.Paste")
			(net "NC_P0V9_RETIMER_CPU1_IMON6")
		)
		(pad "2" smd circle
			(at -0.40005 0 90)
			(size 0 0)
			(layers "B.Cu" "B.Mask" "B.Paste")
			(net "GND")
		)
	)
	(footprint ""
		(layer "B.Cu")
		(at 295.257982 -346.784168 90)
		(property "Reference" "PC159_2"
			(at 0 0 90)
			(layer "B.SilkS")
			(hide yes)
			(effects
				(font
					(size 1.27 1.27)
				)
				(justify mirror)
			)
		)
		(property "Value" ""
			(at 0 0 90)
			(layer "B.Fab")
			(effects
				(font
					(size 1.27 1.27)
				)
				(justify mirror)
			)
		)
		(duplicate_pad_numbers_are_jumpers no)
		(fp_line
			(start 1.524 -0.762)
			(end -1.524 -0.762)
			(stroke
				(width 0.1524)
				(type default)
			)
			(layer "B.SilkS")
		)
		(fp_line
			(start -1.524 -0.762)
			(end -1.524 0.762)
			(stroke
				(width 0.1524)
				(type default)
			)
			(layer "B.SilkS")
		)
		(fp_line
			(start 1.524 0.762)
			(end 1.524 -0.762)
			(stroke
				(width 0.1524)
				(type default)
			)
			(layer "B.SilkS")
		)
		(fp_line
			(start -1.524 0.762)
			(end 1.524 0.762)
			(stroke
				(width 0.1524)
				(type default)
			)
			(layer "B.SilkS")
		)
		(fp_line
			(start 1.1049 -0.724916)
			(end 1.1049 0.724916)
			(stroke
				(width 0.1)
				(type default)
			)
			(layer "B.Fab")
		)
		(fp_line
			(start -1.1049 -0.724916)
			(end 1.1049 -0.724916)
			(stroke
				(width 0.1)
				(type default)
			)
			(layer "B.Fab")
		)
		(fp_line
			(start 1.1049 0.724916)
			(end -1.1049 0.724916)
			(stroke
				(width 0.1)
				(type default)
			)
			(layer "B.Fab")
		)
		(fp_line
			(start -1.1049 0.724916)
			(end -1.1049 -0.724916)
			(stroke
				(width 0.1)
				(type default)
			)
			(layer "B.Fab")
		)
		(pad "1" smd rect
			(at 0.889 0 90)
			(size 1.016 1.27)
			(layers "B.Cu" "B.Mask" "B.Paste")
			(net "SW_P12V_AUX_PVDDIO_P0_FLT")
		)
		(pad "2" smd rect
			(at -0.889 0 90)
			(size 1.016 1.27)
			(layers "B.Cu" "B.Mask" "B.Paste")
			(net "GND")
		)
	)
	(footprint ""
		(layer "B.Cu")
		(at 233.172 -234.569 -90)
		(property "Reference" "C24"
			(at 0 0 90)
			(layer "B.SilkS")
			(hide yes)
			(effects
				(font
					(size 1.27 1.27)
				)
				(justify mirror)
			)
		)
		(property "Value" ""
			(at 0 0 90)
			(layer "B.Fab")
			(effects
				(font
					(size 1.27 1.27)
				)
				(justify mirror)
			)
		)
		(duplicate_pad_numbers_are_jumpers no)
		(fp_line
			(start -0.7874 0.4064)
			(end 0.7874 0.4064)
			(stroke
				(width 0.1524)
				(type default)
			)
			(layer "B.SilkS")
		)
		(fp_line
			(start 0.7874 0.4064)
			(end 0.7874 -0.4064)
			(stroke
				(width 0.1524)
				(type default)
			)
			(layer "B.SilkS")
		)
		(fp_line
			(start -0.7874 -0.4064)
			(end -0.7874 0.4064)
			(stroke
				(width 0.1524)
				(type default)
			)
			(layer "B.SilkS")
		)
		(fp_line
			(start 0.7874 -0.4064)
			(end -0.7874 -0.4064)
			(stroke
				(width 0.1524)
				(type default)
			)
			(layer "B.SilkS")
		)
		(fp_line
			(start -0.67945 0.3048)
			(end -0.120396 0.3048)
			(stroke
				(width 0.1)
				(type default)
			)
			(layer "B.Fab")
		)
		(fp_line
			(start -0.120396 0.3048)
			(end -0.120396 0.2794)
			(stroke
				(width 0.1)
				(type default)
			)
			(layer "B.Fab")
		)
		(fp_line
			(start 0.12065 0.3048)
			(end 0.67945 0.3048)
			(stroke
				(width 0.1)
				(type default)
			)
			(layer "B.Fab")
		)
		(fp_line
			(start 0.67945 0.3048)
			(end 0.67945 -0.305054)
			(stroke
				(width 0.1)
				(type default)
			)
			(layer "B.Fab")
		)
		(fp_line
			(start -0.120396 0.2794)
			(end 0.12065 0.2794)
			(stroke
				(width 0.1)
				(type default)
			)
			(layer "B.Fab")
		)
		(fp_line
			(start 0.12065 0.2794)
			(end 0.12065 0.3048)
			(stroke
				(width 0.1)
				(type default)
			)
			(layer "B.Fab")
		)
		(fp_line
			(start -0.12065 -0.2794)
			(end -0.12065 -0.3048)
			(stroke
				(width 0.1)
				(type default)
			)
			(layer "B.Fab")
		)
		(fp_line
			(start 0.12065 -0.2794)
			(end -0.12065 -0.2794)
			(stroke
				(width 0.1)
				(type default)
			)
			(layer "B.Fab")
		)
		(fp_line
			(start -0.67945 -0.3048)
			(end -0.67945 0.3048)
			(stroke
				(width 0.1)
				(type default)
			)
			(layer "B.Fab")
		)
		(fp_line
			(start -0.12065 -0.3048)
			(end -0.67945 -0.3048)
			(stroke
				(width 0.1)
				(type default)
			)
			(layer "B.Fab")
		)
		(fp_line
			(start 0.12065 -0.305054)
			(end 0.12065 -0.2794)
			(stroke
				(width 0.1)
				(type default)
			)
			(layer "B.Fab")
		)
		(fp_line
			(start 0.67945 -0.305054)
			(end 0.12065 -0.305054)
			(stroke
				(width 0.1)
				(type default)
			)
			(layer "B.Fab")
		)
		(pad "1" smd circle
			(at 0.40005 0 90)
			(size 0 0)
			(layers "B.Cu" "B.Mask" "B.Paste")
			(net "PVDD18_S5_P0")
		)
		(pad "2" smd circle
			(at -0.40005 0 90)
			(size 0 0)
			(layers "B.Cu" "B.Mask" "B.Paste")
			(net "GND")
		)
	)
	(footprint ""
		(layer "B.Cu")
		(at 255.905 -341.884 180)
		(property "Reference" "R797"
			(at 0 0 0)
			(layer "B.SilkS")
			(hide yes)
			(effects
				(font
					(size 1.27 1.27)
				)
				(justify mirror)
			)
		)
		(property "Value" ""
			(at 0 0 0)
			(layer "B.Fab")
			(effects
				(font
					(size 1.27 1.27)
				)
				(justify mirror)
			)
		)
		(duplicate_pad_numbers_are_jumpers no)
		(fp_line
			(start 0.32512 0.175006)
			(end 0.32512 -0.175006)
			(stroke
				(width 0.1)
				(type default)
			)
			(layer "B.Fab")
		)
		(fp_line
			(start 0.32512 -0.175006)
			(end -0.32512 -0.175006)
			(stroke
				(width 0.1)
				(type default)
			)
			(layer "B.Fab")
		)
		(fp_line
			(start -0.32512 0.175006)
			(end 0.32512 0.175006)
			(stroke
				(width 0.1)
				(type default)
			)
			(layer "B.Fab")
		)
		(fp_line
			(start -0.32512 -0.175006)
			(end -0.32512 0.175006)
			(stroke
				(width 0.1)
				(type default)
			)
			(layer "B.Fab")
		)
		(pad "1" smd rect
			(at 0.2667 0)
			(size 0.3048 0.381)
			(layers "B.Cu" "B.Mask" "B.Paste")
			(net "SMB_RT_CPU0_P0_ROM_MUX_2D_R_SDA")
		)
		(pad "2" smd rect
			(at -0.2667 0 180)
			(size 0.3048 0.381)
			(layers "B.Cu" "B.Mask" "B.Paste")
			(net "SMB_RT_CPU0_P0_ROM_MUX_2D_SDA")
		)
	)
	(footprint ""
		(layer "B.Cu")
		(at 330.523342 -392.1252 180)
		(property "Reference" "R1021"
			(at 0 0 0)
			(layer "B.SilkS")
			(hide yes)
			(effects
				(font
					(size 1.27 1.27)
				)
				(justify mirror)
			)
		)
		(property "Value" ""
			(at 0 0 0)
			(layer "B.Fab")
			(effects
				(font
					(size 1.27 1.27)
				)
				(justify mirror)
			)
		)
		(duplicate_pad_numbers_are_jumpers no)
		(fp_line
			(start 0.32512 0.175006)
			(end 0.32512 -0.175006)
			(stroke
				(width 0.1)
				(type default)
			)
			(layer "B.Fab")
		)
		(fp_line
			(start 0.32512 -0.175006)
			(end -0.32512 -0.175006)
			(stroke
				(width 0.1)
				(type default)
			)
			(layer "B.Fab")
		)
		(fp_line
			(start -0.32512 0.175006)
			(end 0.32512 0.175006)
			(stroke
				(width 0.1)
				(type default)
			)
			(layer "B.Fab")
		)
		(fp_line
			(start -0.32512 -0.175006)
			(end -0.32512 0.175006)
			(stroke
				(width 0.1)
				(type default)
			)
			(layer "B.Fab")
		)
		(pad "1" smd rect
			(at 0.2667 0)
			(size 0.3048 0.381)
			(layers "B.Cu" "B.Mask" "B.Paste")
			(net "P1V8_CPU0_RT_1D")
		)
		(pad "2" smd rect
			(at -0.2667 0 180)
			(size 0.3048 0.381)
			(layers "B.Cu" "B.Mask" "B.Paste")
			(net "RT_CPU0_P1_SCAN_MODE")
		)
	)
	(footprint ""
		(layer "B.Cu")
		(at 111.47806 -35.088068 90)
		(property "Reference" "C6111"
			(at 0 0 90)
			(layer "B.SilkS")
			(hide yes)
			(effects
				(font
					(size 1.27 1.27)
				)
				(justify mirror)
			)
		)
		(property "Value" ""
			(at 0 0 90)
			(layer "B.Fab")
			(effects
				(font
					(size 1.27 1.27)
				)
				(justify mirror)
			)
		)
		(duplicate_pad_numbers_are_jumpers no)
		(fp_line
			(start 0.7874 -0.4064)
			(end -0.7874 -0.4064)
			(stroke
				(width 0.1524)
				(type default)
			)
			(layer "B.SilkS")
		)
		(fp_line
			(start -0.7874 -0.4064)
			(end -0.7874 0.4064)
			(stroke
				(width 0.1524)
				(type default)
			)
			(layer "B.SilkS")
		)
		(fp_line
			(start 0.7874 0.4064)
			(end 0.7874 -0.4064)
			(stroke
				(width 0.1524)
				(type default)
			)
			(layer "B.SilkS")
		)
		(fp_line
			(start -0.7874 0.4064)
			(end 0.7874 0.4064)
			(stroke
				(width 0.1524)
				(type default)
			)
			(layer "B.SilkS")
		)
		(fp_line
			(start 0.67945 -0.305054)
			(end 0.12065 -0.305054)
			(stroke
				(width 0.1)
				(type default)
			)
			(layer "B.Fab")
		)
		(fp_line
			(start 0.12065 -0.305054)
			(end 0.12065 -0.2794)
			(stroke
				(width 0.1)
				(type default)
			)
			(layer "B.Fab")
		)
		(fp_line
			(start -0.12065 -0.3048)
			(end -0.67945 -0.3048)
			(stroke
				(width 0.1)
				(type default)
			)
			(layer "B.Fab")
		)
		(fp_line
			(start -0.67945 -0.3048)
			(end -0.67945 0.3048)
			(stroke
				(width 0.1)
				(type default)
			)
			(layer "B.Fab")
		)
		(fp_line
			(start 0.12065 -0.2794)
			(end -0.12065 -0.2794)
			(stroke
				(width 0.1)
				(type default)
			)
			(layer "B.Fab")
		)
		(fp_line
			(start -0.12065 -0.2794)
			(end -0.12065 -0.3048)
			(stroke
				(width 0.1)
				(type default)
			)
			(layer "B.Fab")
		)
		(fp_line
			(start 0.12065 0.2794)
			(end 0.12065 0.3048)
			(stroke
				(width 0.1)
				(type default)
			)
			(layer "B.Fab")
		)
		(fp_line
			(start -0.120396 0.2794)
			(end 0.12065 0.2794)
			(stroke
				(width 0.1)
				(type default)
			)
			(layer "B.Fab")
		)
		(fp_line
			(start 0.67945 0.3048)
			(end 0.67945 -0.305054)
			(stroke
				(width 0.1)
				(type default)
			)
			(layer "B.Fab")
		)
		(fp_line
			(start 0.12065 0.3048)
			(end 0.67945 0.3048)
			(stroke
				(width 0.1)
				(type default)
			)
			(layer "B.Fab")
		)
		(fp_line
			(start -0.120396 0.3048)
			(end -0.120396 0.2794)
			(stroke
				(width 0.1)
				(type default)
			)
			(layer "B.Fab")
		)
		(fp_line
			(start -0.67945 0.3048)
			(end -0.120396 0.3048)
			(stroke
				(width 0.1)
				(type default)
			)
			(layer "B.Fab")
		)
		(pad "1" smd circle
			(at 0.40005 0 270)
			(size 0 0)
			(layers "B.Cu" "B.Mask" "B.Paste")
			(net "P1V2_CPU0_USB2_DVDD12")
		)
		(pad "2" smd circle
			(at -0.40005 0 270)
			(size 0 0)
			(layers "B.Cu" "B.Mask" "B.Paste")
			(net "GND")
		)
	)
	(footprint ""
		(layer "B.Cu")
		(at 304.718212 -396.393162 -90)
		(property "Reference" "C523"
			(at 0 0 90)
			(layer "B.SilkS")
			(hide yes)
			(effects
				(font
					(size 1.27 1.27)
				)
				(justify mirror)
			)
		)
		(property "Value" ""
			(at 0 0 90)
			(layer "B.Fab")
			(effects
				(font
					(size 1.27 1.27)
				)
				(justify mirror)
			)
		)
		(duplicate_pad_numbers_are_jumpers no)
		(fp_line
			(start -0.299974 0.150114)
			(end 0.299974 0.150114)
			(stroke
				(width 0.1)
				(type default)
			)
			(layer "B.Fab")
		)
		(fp_line
			(start 0.299974 0.150114)
			(end 0.299974 -0.150114)
			(stroke
				(width 0.1)
				(type default)
			)
			(layer "B.Fab")
		)
		(fp_line
			(start -0.299974 -0.150114)
			(end -0.299974 0.150114)
			(stroke
				(width 0.1)
				(type default)
			)
			(layer "B.Fab")
		)
		(fp_line
			(start 0.299974 -0.150114)
			(end -0.299974 -0.150114)
			(stroke
				(width 0.1)
				(type default)
			)
			(layer "B.Fab")
		)
		(pad "1" smd rect
			(at 0.2667 0 90)
			(size 0.3048 0.381)
			(layers "B.Cu" "B.Mask" "B.Paste")
			(net "P0V9_CPU0_RT0_2A")
		)
		(pad "2" smd rect
			(at -0.2667 0 90)
			(size 0.3048 0.381)
			(layers "B.Cu" "B.Mask" "B.Paste")
			(net "GND")
		)
	)
)
